# T6G (Grand Teton) — schematic netlist excerpt (pin names and nets, part order shuffled) for the footprints in the layout excerpt that follows; sources: Cadence DE-HDL packaged netlist, KiCad conversion of 04192023_DAF0TMB3IC0_F0TG_MB_C_brd_V02_OCP.brd

C2152  Q_CAP  22UF 4V 20% X6S  pkg C0402  page 68 : A = PVDDCR_SOC_P0 ; B = GND
C2109  Q_CAP  22UF 4V 20% X6S  pkg C0402  page 74 : A = PVDDIO_P1 ; B = GND

(kicad_pcb
	(version 20260206)
	(generator "pcbnew")
	(generator_version "10.0")
	(general
		(thickness 1.6)
		(legacy_teardrops no)
	)
	(paper "A4")
	(title_block
		(title "04192023_DAF0TMB3IC0_F0TG_MB_C_brd_V02_OCP.brd")
		(comment 1 "Grand Teton / footprints 5243-5244 of 8354")
	)
	(layers
		(0 "F.Cu" signal "TOP")
		(4 "In1.Cu" signal "GND")
		(6 "In2.Cu" signal "IN1")
		(8 "In3.Cu" signal "GND1")
		(10 "In4.Cu" signal "IN2")
		(12 "In5.Cu" signal "GND2")
		(14 "In6.Cu" signal "IN3")
		(16 "In7.Cu" signal "GND3")
		(18 "In8.Cu" signal "VCC")
		(20 "In9.Cu" signal "VCC1")
		(22 "In10.Cu" signal "GND4")
		(24 "In11.Cu" signal "IN4")
		(26 "In12.Cu" signal "GND5")
		(28 "In13.Cu" signal "IN5")
		(30 "In14.Cu" signal "GND6")
		(32 "In15.Cu" signal "IN6")
		(34 "In16.Cu" signal "GND7")
		(2 "B.Cu" signal "BOTTOM")
		(9 "F.Adhes" user "F.Adhesive")
		(11 "B.Adhes" user "B.Adhesive")
		(13 "F.Paste" user "Package Geometry/Pastemask Top")
		(15 "B.Paste" user "Package Geometry/Pastemask Bottom")
		(5 "F.SilkS" user "Ref Des/Silkscreen Top")
		(7 "B.SilkS" user "Ref Des/Silkscreen Bottom")
		(1 "F.Mask" user "Board Geometry/Soldermask Top")
		(3 "B.Mask" user "Board Geometry/Soldermask Bottom")
		(17 "Dwgs.User" user "User.Drawings")
		(19 "Cmts.User" user "User.Comments")
		(21 "Eco1.User" user "User.Eco1")
		(23 "Eco2.User" user "User.Eco2")
		(25 "Edge.Cuts" user "Board Geometry/Outline")
		(27 "Margin" user)
		(31 "F.CrtYd" user "Package Geometry/Place Bound Top")
		(29 "B.CrtYd" user "Package Geometry/Place Bound Bottom")
		(35 "F.Fab" user "Ref Des/Assembly Top")
		(33 "B.Fab" user "Ref Des/Assembly Bottom")
	)
	(footprint ""
		(layer "B.Cu")
		(at 98.578924 -258.830318 180)
		(property "Reference" "C2109"
			(at 0 0 0)
			(layer "B.SilkS")
			(hide yes)
			(effects
				(font
					(size 1.27 1.27)
				)
				(justify mirror)
			)
		)
		(property "Value" ""
			(at 0 0 0)
			(layer "B.Fab")
			(effects
				(font
					(size 1.27 1.27)
				)
				(justify mirror)
			)
		)
		(duplicate_pad_numbers_are_jumpers no)
		(fp_line
			(start 0.7874 0.4064)
			(end 0.7874 -0.4064)
			(stroke
				(width 0.1524)
				(type default)
			)
			(layer "B.SilkS")
		)
		(fp_line
			(start 0.7874 -0.4064)
			(end -0.7874 -0.4064)
			(stroke
				(width 0.1524)
				(type default)
			)
			(layer "B.SilkS")
		)
		(fp_line
			(start -0.7874 0.4064)
			(end 0.7874 0.4064)
			(stroke
				(width 0.1524)
				(type default)
			)
			(layer "B.SilkS")
		)
		(fp_line
			(start -0.7874 -0.4064)
			(end -0.7874 0.4064)
			(stroke
				(width 0.1524)
				(type default)
			)
			(layer "B.SilkS")
		)
		(fp_line
			(start 0.67945 0.3048)
			(end 0.67945 -0.305054)
			(stroke
				(width 0.1)
				(type default)
			)
			(layer "B.Fab")
		)
		(fp_line
			(start 0.67945 -0.305054)
			(end 0.12065 -0.305054)
			(stroke
				(width 0.1)
				(type default)
			)
			(layer "B.Fab")
		)
		(fp_line
			(start 0.12065 0.3048)
			(end 0.67945 0.3048)
			(stroke
				(width 0.1)
				(type default)
			)
			(layer "B.Fab")
		)
		(fp_line
			(start 0.12065 0.2794)
			(end 0.12065 0.3048)
			(stroke
				(width 0.1)
				(type default)
			)
			(layer "B.Fab")
		)
		(fp_line
			(start 0.12065 -0.2794)
			(end -0.12065 -0.2794)
			(stroke
				(width 0.1)
				(type default)
			)
			(layer "B.Fab")
		)
		(fp_line
			(start 0.12065 -0.305054)
			(end 0.12065 -0.2794)
			(stroke
				(width 0.1)
				(type default)
			)
			(layer "B.Fab")
		)
		(fp_line
			(start -0.120396 0.3048)
			(end -0.120396 0.2794)
			(stroke
				(width 0.1)
				(type default)
			)
			(layer "B.Fab")
		)
		(fp_line
			(start -0.120396 0.2794)
			(end 0.12065 0.2794)
			(stroke
				(width 0.1)
				(type default)
			)
			(layer "B.Fab")
		)
		(fp_line
			(start -0.12065 -0.2794)
			(end -0.12065 -0.3048)
			(stroke
				(width 0.1)
				(type default)
			)
			(layer "B.Fab")
		)
		(fp_line
			(start -0.12065 -0.3048)
			(end -0.67945 -0.3048)
			(stroke
				(width 0.1)
				(type default)
			)
			(layer "B.Fab")
		)
		(fp_line
			(start -0.67945 0.3048)
			(end -0.120396 0.3048)
			(stroke
				(width 0.1)
				(type default)
			)
			(layer "B.Fab")
		)
		(fp_line
			(start -0.67945 -0.3048)
			(end -0.67945 0.3048)
			(stroke
				(width 0.1)
				(type default)
			)
			(layer "B.Fab")
		)
		(pad "1" smd circle
			(at 0.40005 0)
			(size 0 0)
			(layers "B.Cu" "B.Mask" "B.Paste")
			(net "PVDDIO_P1")
		)
		(pad "2" smd circle
			(at -0.40005 0)
			(size 0 0)
			(layers "B.Cu" "B.Mask" "B.Paste")
			(net "GND")
		)
	)
	(footprint ""
		(layer "B.Cu")
		(at 365.835692 -255.554988)
		(property "Reference" "C2152"
			(at 0 0 0)
			(layer "B.SilkS")
			(hide yes)
			(effects
				(font
					(size 1.27 1.27)
				)
				(justify mirror)
			)
		)
		(property "Value" ""
			(at 0 0 0)
			(layer "B.Fab")
			(effects
				(font
					(size 1.27 1.27)
				)
				(justify mirror)
			)
		)
		(duplicate_pad_numbers_are_jumpers no)
		(fp_line
			(start -0.7874 -0.4064)
			(end -0.7874 0.4064)
			(stroke
				(width 0.1524)
				(type default)
			)
			(layer "B.SilkS")
		)
		(fp_line
			(start -0.7874 0.4064)
			(end 0.7874 0.4064)
			(stroke
				(width 0.1524)
				(type default)
			)
			(layer "B.SilkS")
		)
		(fp_line
			(start 0.7874 -0.4064)
			(end -0.7874 -0.4064)
			(stroke
				(width 0.1524)
				(type default)
			)
			(layer "B.SilkS")
		)
		(fp_line
			(start 0.7874 0.4064)
			(end 0.7874 -0.4064)
			(stroke
				(width 0.1524)
				(type default)
			)
			(layer "B.SilkS")
		)
		(fp_line
			(start -0.67945 -0.3048)
			(end -0.67945 0.3048)
			(stroke
				(width 0.1)
				(type default)
			)
			(layer "B.Fab")
		)
		(fp_line
			(start -0.67945 0.3048)
			(end -0.120396 0.3048)
			(stroke
				(width 0.1)
				(type default)
			)
			(layer "B.Fab")
		)
		(fp_line
			(start -0.12065 -0.3048)
			(end -0.67945 -0.3048)
			(stroke
				(width 0.1)
				(type default)
			)
			(layer "B.Fab")
		)
		(fp_line
			(start -0.12065 -0.2794)
			(end -0.12065 -0.3048)
			(stroke
				(width 0.1)
				(type default)
			)
			(layer "B.Fab")
		)
		(fp_line
			(start -0.120396 0.2794)
			(end 0.12065 0.2794)
			(stroke
				(width 0.1)
				(type default)
			)
			(layer "B.Fab")
		)
		(fp_line
			(start -0.120396 0.3048)
			(end -0.120396 0.2794)
			(stroke
				(width 0.1)
				(type default)
			)
			(layer "B.Fab")
		)
		(fp_line
			(start 0.12065 -0.305054)
			(end 0.12065 -0.2794)
			(stroke
				(width 0.1)
				(type default)
			)
			(layer "B.Fab")
		)
		(fp_line
			(start 0.12065 -0.2794)
			(end -0.12065 -0.2794)
			(stroke
				(width 0.1)
				(type default)
			)
			(layer "B.Fab")
		)
		(fp_line
			(start 0.12065 0.2794)
			(end 0.12065 0.3048)
			(stroke
				(width 0.1)
				(type default)
			)
			(layer "B.Fab")
		)
		(fp_line
			(start 0.12065 0.3048)
			(end 0.67945 0.3048)
			(stroke
				(width 0.1)
				(type default)
			)
			(layer "B.Fab")
		)
		(fp_line
			(start 0.67945 -0.305054)
			(end 0.12065 -0.305054)
			(stroke
				(width 0.1)
				(type default)
			)
			(layer "B.Fab")
		)
		(fp_line
			(start 0.67945 0.3048)
			(end 0.67945 -0.305054)
			(stroke
				(width 0.1)
				(type default)
			)
			(layer "B.Fab")
		)
		(pad "1" smd circle
			(at 0.40005 0 180)
			(size 0 0)
			(layers "B.Cu" "B.Mask" "B.Paste")
			(net "PVDDCR_SOC_P0")
		)
		(pad "2" smd circle
			(at -0.40005 0 180)
			(size 0 0)
			(layers "B.Cu" "B.Mask" "B.Paste")
			(net "GND")
		)
	)
)
